# S9S_MB_2U (Grand Teton) — schematic parts with pin connectivity, parts 3650–3801 of 6093; source: Cadence DE-HDL packaged netlist (pstxprt.dat, pstxnet.dat, pstchip.dat)

R693  Q_RES  0 5% CHIP  pkg 0402LF  page 229 : 1 = I3C_SPD_DDREFGH_CPU0_LVC1_R_SCL ; 2 = I3C_SPD_DDREFGH_CPU0_LVC1_SCL
R694  Q_RES  33.2 1% CHIP  pkg 0402LF  page 229 : 1 = I3C_SPD_DDREFGH_CPU0_LVC1_R_SDA ; 2 = I3C_SPD_DDREFGH_CPU0_LVC1_SDA
R696  Q_RES  4.75K 1% CHIP  pkg 0402LF  page 182 : 1 = P3V3_AUX ; 2 = RST_PCH_RSTBTN_R_N
R697  Q_RES  33.2 1% CHIP  pkg 0402LF  page 182 : 1 = FM_BMC_RSTBTN_OUT_N ; 2 = RST_PCH_RSTBTN_R_N
R698  Q_RES  49.9 1% CHIP  pkg 0402LF  page 205 : 1 = FM_ADR_TRIGGER_R_N ; 2 = FM_ADR_TRIGGER_N
R699  Q_RES  33.2 1% CHIP  pkg 0402LF  page 183 : 1 = FM_PCH_CRASHLOG_TRIG_R_N ; 2 = FM_PCH_CRASHLOG_TRIG_N
R700  Q_RES  0 5% CHIP  pkg 0402LF  page 215 : 1 = FM_ADR_ACK_R ; 2 = FM_ADR_ACK
R701  Q_RES  10K 1% EMPTY  pkg 0402LF  page 130 : 1 = RST_PLD_CPU1_DRAM_CD_N ; 2 = GND
R702  Q_RES  10K 1% EMPTY  pkg 0402LF  page 130 : 1 = RST_PLD_CPU1_DRAM_GH_N ; 2 = GND
R703  Q_RES  10K 1% EMPTY  pkg 0402LF  page 130 : 1 = RST_PLD_CPU1_DRAM_AB_N ; 2 = GND
R704  Q_RES  10K 1% EMPTY  pkg 0402LF  page 130 : 1 = RST_PLD_CPU1_DRAM_EF_N ; 2 = GND
R705  Q_RES  10K 1% EMPTY  pkg 0402LF  page 129 : 1 = RST_PLD_CPU0_DRAM_GH_N ; 2 = GND
R706  Q_RES  10K 1% EMPTY  pkg 0402LF  page 129 : 1 = RST_PLD_CPU0_DRAM_AB_N ; 2 = GND
R707  Q_RES  10K 1% EMPTY  pkg 0402LF  page 129 : 1 = RST_PLD_CPU0_DRAM_CD_N ; 2 = GND
R708  Q_RES  10K 1% EMPTY  pkg 0402LF  page 129 : 1 = RST_PLD_CPU0_DRAM_EF_N ; 2 = GND
R710  Q_RES  1K 1% CHIP  pkg 0402LF  page 243 : 1 = PD_MB_FRU_WP ; 2 = GND
R713  Q_RES  10K 1% EMPTY  pkg 0402LF  page 243 : 1 = P3V3_AUX ; 2 = MB_FRU_ADDR2
R714  Q_RES  1K 1% CHIP  pkg 0402LF  page 243 : 1 = MB_FRU_ADDR2 ; 2 = GND
R717  Q_RES  10K 1% EMPTY  pkg 0402LF  page 243 : 1 = P3V3_AUX ; 2 = MB_FRU_ADDR1
R718  Q_RES  1K 1% CHIP  pkg 0402LF  page 243 : 1 = MB_FRU_ADDR1 ; 2 = GND
R721  Q_RES  10K 1% CHIP  pkg 0402LF  page 243 : 1 = P3V3_AUX ; 2 = MB_FRU_ADDR0
R722  Q_RES  1K 1% EMPTY  pkg 0402LF  page 243 : 1 = MB_FRU_ADDR0 ; 2 = GND
R727  Q_RES  10K 1% CHIP  pkg 0402LF  page 183 : 1 = PU_OC4_USB_N ; 2 = P3V3_AUX
R734  Q_RES  4.75K 1% CHIP  pkg 0402LF  page 208 : 1 = CLK_CK440_SMB_ADDR1 ; 2 = GND
R735  Q_RES  10K 1% CHIP  pkg 0402LF  page 220 : 1 = P3V3_AUX ; 2 = FM_DIMM_12V_CPS_SX_N
R736  Q_RES  1K 1% EMPTY  pkg 0402LF  page 220 : 1 = FM_DIMM_12V_CPS_SX_N ; 2 = GND
R737  Q_RES  0 5% CHIP  pkg 0402LF  page 133 : 1 = FM_CPU1_SKTOCC_LVT3_N ; 2 = FM_CPU1_SKTOCC_N
R738  Q_RES  0 5% CHIP  pkg 0402LF  page 133 : 1 = FM_CPU0_SKTOCC_LVT3_N ; 2 = FM_CPU0_SKTOCC_N
R739  Q_RES  10K 1% CHIP  pkg 0402LF  page 133 : 1 = P3V3_AUX ; 2 = FM_CPU1_SKTOCC_N
R740  Q_RES  10K 1% CHIP  pkg 0402LF  page 133 : 1 = P3V3_AUX ; 2 = FM_CPU0_SKTOCC_N
R741  Q_RES  150 1% CHIP  pkg 0402LF  page 133 : 1 = PVNN_TERM_CPU0 ; 2 = JTAG_MUX_CPU0_GTL_TDI
R742  Q_RES  75 1% CHIP  pkg 0402LF  page 133 : 1 = PVNN_TERM_CPU1 ; 2 = JTAG_CPU1_MUX_GTL_TDO
R743  Q_RES  150 1% CHIP  pkg 0402LF  page 133 : 1 = PVNN_TERM_CPU1 ; 2 = JTAG_MUX_CPU1_GTL_TDI
R744  Q_RES  75 1% CHIP  pkg 0402LF  page 133 : 1 = PVNN_TERM_CPU0 ; 2 = JTAG_CPU0_MUX_GTL_TDO
R745  Q_RES  33.2 1% CHIP  pkg 0402LF  page 133 : 1 = FM_CPU_EN ; 2 = FM_CPU_EN_R
R746  Q_RES  0 5% CHIP  pkg 0402LF  page 132 : 1 = PD_74CB_A9 ; 2 = GND
R747  Q_RES  150 1% CHIP  pkg 0402LF  page 132 : 1 = P1V05_PCH_AUX ; 2 = JTAG_DBP_TDO_PCH
R748  Q_RES  75 1% CHIP  pkg 0402LF  page 132 : 1 = P1V05_PCH_AUX ; 2 = JTAG_DBP_TDI_PCH
R749  Q_RES  75 1% CHIP  pkg 0402LF  page 132 : 1 = P1V05_PCH_AUX ; 2 = JTAG_DBP_TMS_PCH
R750  Q_RES  150 1% CHIP  pkg 0402LF  page 132 : 1 = P1V05_PCH_AUX ; 2 = H_DBP_PREQ_N_PCH
R751  Q_RES  150 1% CHIP  pkg 0402LF  page 132 : 1 = P1V05_PCH_AUX ; 2 = H_DBP_PRDY_N_PCH
R752  Q_RES  10 1% CHIP  pkg 0402LF  page 132 : 1 = JTAG_DBP_TDO ; 2 = JTAG_DBP_TDO_PCH
R753  Q_RES  10 1% CHIP  pkg 0402LF  page 132 : 1 = JTAG_DBP_TDI ; 2 = JTAG_DBP_TDI_PCH
R754  Q_RES  10 1% CHIP  pkg 0402LF  page 132 : 1 = JTAG_DBP_TMS ; 2 = JTAG_DBP_TMS_PCH
R755  Q_RES  10 1% CHIP  pkg 0402LF  page 132 : 1 = JTAG_DBP_PREQ_N ; 2 = H_DBP_PREQ_N_PCH
R756  Q_RES  10 1% CHIP  pkg 0402LF  page 132 : 1 = JTAG_DBP_PRDY_N ; 2 = H_DBP_PRDY_N_PCH
R757  Q_RES  120 1% CHIP  pkg 0402LF  page 132 : 1 = PVNN_TERM_CPU0 ; 2 = JTAG_DBP_CPU_QS_GTL_TMS
R758  Q_RES  150 1% CHIP  pkg 0402LF  page 132 : 1 = PVNN_TERM_CPU0 ; 2 = H_CPU_PREQ_QS_GTL_N
R759  Q_RES  150 1% CHIP  pkg 0402LF  page 132 : 1 = PVNN_TERM_CPU0 ; 2 = H_CPU_PRDY_QS_GTL_N
R760  Q_RES  499 1% CHIP  pkg 0402LF  page 132 : 1 = PVNN_TERM_CPU0 ; 2 = DBP_CPU_HOOK8_MBP2_GTL_QS_N
R761  Q_RES  499 1% CHIP  pkg 0402LF  page 132 : 1 = PVNN_TERM_CPU0 ; 2 = DBP_CPU_HOOK9_MBP3_GTL_QS_N
R762  Q_RES  0 5% CHIP  pkg 0402LF  page 131 : 1 = JTAG_DBP_CPU_GTL_TCK ; 2 = JTAG_DBP_CPU_GTL_TCK_R
R763  Q_RES  10 1% CHIP  pkg 0402LF  page 131 : 1 = JTAG_DBP_TDI ; 2 = JTAG_DBP_TDI_R
R764  Q_RES  0 5% CHIP  pkg 0402LF  page 131 : 1 = JTAG_DBP_PRDY_N ; 2 = JTAG_DBP_PRDY_R1_N
R765  Q_RES  0 5% CHIP  pkg 0402LF  page 131 : 1 = JTAG_DBP_TCK_PCH ; 2 = JTAG_DBP_TCK_R_TCK
R766  Q_RES  1K 1% EMPTY  pkg 0402LF  page 131 : 1 = P3V3_AUX ; 2 = JTAG_DBP_POWER_BTN_N
R767  Q_RES  1K 1% CHIP  pkg 0402LF  page 131 : 1 = P3V3_AUX ; 2 = JTAG_RST_DBP_RST_CO_N
R768  Q_RES  1K 1% CHIP  pkg 0402LF  page 131 : 1 = P3V3_AUX ; 2 = JTAG_DBP_PRESENT_R_N
R769  Q_RES  10K 1% CHIP  pkg 0402LF  page 131 : 1 = PD_TRST_P3 ; 2 = GND
R770  Q_RES  10K 1% CHIP  pkg 0402LF  page 183 : 1 = PU_OC5_USB_N ; 2 = P3V3_AUX
R771  Q_RES  1K 1% CHIP  pkg 0402LF  page 131 : 1 = JTAG_DBP_PCH_DEBUG_CONSENT_N ; 2 = FM_PCH_CONSENT_STRAP_N
R772  Q_RES  1K 1% CHIP  pkg 0402LF  page 131 : 1 = JTAG_RST_DBP_RSMRST_N ; 2 = RST_RSMRST_PCH_N
R773  Q_RES  1K 1% CHIP  pkg 0402LF  page 131 : 1 = JTAG_DBP_BOOT_HALT_N ; 2 = FM_ADR_MODE0
R774  Q_RES  75 1% CHIP  pkg 0402LF  page 131 : 1 = JTAG_DBP_CPU_GTL_TCK ; 2 = GND
R775  Q_RES  10 1% CHIP  pkg 0402LF  page 131 : 1 = JTAG_DBP_TMS_R ; 2 = JTAG_DBP_TMS
R776  Q_RES  100 1% CHIP  pkg 0402LF  page 131 : 1 = JTAG_DBP_TDO_R ; 2 = JTAG_DBP_TDO
R777  Q_RES  10 1% CHIP  pkg 0402LF  page 131 : 1 = JTAG_DBP_PREQ_N_R ; 2 = JTAG_DBP_PREQ_N
R778  Q_RES  1K 1% CHIP  pkg 0402LF  page 131 : 1 = P3V3_AUX ; 2 = JTAG_DBP_BOOT_HALT_N
R779  Q_RES  150 1% CHIP  pkg 0402LF  page 131 : 1 = PVNN_TERM_CPU0 ; 2 = FM_CPU_FBRK_DEBUG_N
R780  Q_RES  49.9 1% CHIP  pkg 0402LF  page 131 : 1 = FM_CPU_FBRK_DEBUG_N ; 2 = FM_CPU_FBRK_DEBUG_R_N
R803  Q_RES  33.2 1% CHIP  pkg 0402LF  page 221 : 1 = JTAG_PLD_TDI_R ; 2 = JTAG_BMC_PLD_TDI
R804  Q_RES  33.2 1% CHIP  pkg 0402LF  page 221 : 1 = JTAG_PLD_TDO_R ; 2 = JTAG_BMC_PLD_TDO
R805  Q_RES  33.2 1% CHIP  pkg 0402LF  page 221 : 1 = JTAG_PLD_TMS_R ; 2 = JTAG_BMC_PLD_TMS
R806  Q_RES  33.2 1% CHIP  pkg 0402LF  page 221 : 1 = JTAG_PLD_TCK_R ; 2 = JTAG_BMC_PLD_TCK
R815  Q_RES  0 5% CHIP  pkg 0402LF  page 130 : 1 = RST_PLD_CPU1_DRAM_GH_N ; 2 = RST_M_GH_CPU1_FPGA_N
R816  Q_RES  0 5% CHIP  pkg 0402LF  page 130 : 1 = RST_PLD_CPU1_DRAM_AB_N ; 2 = RST_M_AB_CPU1_FPGA_N
R817  Q_RES  0 5% CHIP  pkg 0402LF  page 130 : 1 = RST_PLD_CPU1_DRAM_CD_N ; 2 = RST_M_CD_CPU1_FPGA_N
R818  Q_RES  0 5% CHIP  pkg 0402LF  page 130 : 1 = RST_PLD_CPU1_DRAM_EF_N ; 2 = RST_M_EF_CPU1_FPGA_N
R819  Q_RES  1K 1% CHIP  pkg 0402LF  page 130 : 1 = PVCCD_HV_CPU1 ; 2 = RST_M_GH_CPU1_FPGA_N
R820  Q_RES  1K 1% CHIP  pkg 0402LF  page 130 : 1 = PVCCD_HV_CPU1 ; 2 = RST_M_AB_CPU1_FPGA_N
R821  Q_RES  1K 1% CHIP  pkg 0402LF  page 130 : 1 = PVCCD_HV_CPU1 ; 2 = RST_M_CD_CPU1_FPGA_N
R822  Q_RES  1K 1% CHIP  pkg 0402LF  page 130 : 1 = PVCCD_HV_CPU1 ; 2 = RST_M_EF_CPU1_FPGA_N
R835  Q_RES  0 5% CHIP  pkg 0402LF  page 129 : 1 = RST_PLD_CPU0_DRAM_GH_N ; 2 = RST_M_GH_CPU0_FPGA_N
R836  Q_RES  0 5% CHIP  pkg 0402LF  page 129 : 1 = RST_PLD_CPU0_DRAM_AB_N ; 2 = RST_M_AB_CPU0_FPGA_N
R837  Q_RES  0 5% CHIP  pkg 0402LF  page 129 : 1 = RST_PLD_CPU0_DRAM_CD_N ; 2 = RST_M_CD_CPU0_FPGA_N
R838  Q_RES  0 5% CHIP  pkg 0402LF  page 129 : 1 = RST_PLD_CPU0_DRAM_EF_N ; 2 = RST_M_EF_CPU0_FPGA_N
R839  Q_RES  1K 1% CHIP  pkg 0402LF  page 129 : 1 = PVCCD_HV_CPU0 ; 2 = RST_M_GH_CPU0_FPGA_N
R840  Q_RES  1K 1% CHIP  pkg 0402LF  page 129 : 1 = PVCCD_HV_CPU0 ; 2 = RST_M_AB_CPU0_FPGA_N
R841  Q_RES  1K 1% CHIP  pkg 0402LF  page 129 : 1 = PVCCD_HV_CPU0 ; 2 = RST_M_CD_CPU0_FPGA_N
R842  Q_RES  1K 1% CHIP  pkg 0402LF  page 129 : 1 = PVCCD_HV_CPU0 ; 2 = RST_M_EF_CPU0_FPGA_N
R851  Q_RES  0 5% CHIP  pkg 0402LF  page 128 : 1 = RST_CPU0_DRAM_AB_N ; 2 = RST_CPU0_DRAM_AB_PLD_N
R852  Q_RES  0 5% CHIP  pkg 0402LF  page 128 : 1 = RST_CPU0_DRAM_CD_N ; 2 = RST_CPU0_DRAM_CD_PLD_N
R853  Q_RES  0 5% CHIP  pkg 0402LF  page 128 : 1 = RST_CPU0_DRAM_EF_N ; 2 = RST_CPU0_DRAM_EF_PLD_N
R854  Q_RES  0 5% CHIP  pkg 0402LF  page 128 : 1 = RST_CPU0_DRAM_GH_N ; 2 = RST_CPU0_DRAM_GH_PLD_N
R859  Q_RES  0 5% CHIP  pkg 0402LF  page 128 : 1 = RST_CPU1_DRAM_AB_N ; 2 = RST_CPU1_DRAM_AB_PLD_N
R860  Q_RES  0 5% CHIP  pkg 0402LF  page 128 : 1 = RST_CPU1_DRAM_CD_N ; 2 = RST_CPU1_DRAM_CD_PLD_N
R861  Q_RES  0 5% CHIP  pkg 0402LF  page 128 : 1 = RST_CPU1_DRAM_EF_N ; 2 = RST_CPU1_DRAM_EF_PLD_N
R880  Q_RES  33.2 1% CHIP  pkg 0402LF  page 114 : 1 = PWRGD_CHB_CPU0_DIMM2 ; 2 = PWRGD_FAIL_CPU0_AB
R884  Q_RES  33.2 1% CHIP  pkg 0402LF  page 114 : 1 = PWRGD_CHD_CPU0_DIMM2 ; 2 = PWRGD_FAIL_CPU0_CD
R885  Q_RES  33.2 1% CHIP  pkg 0402LF  page 114 : 1 = PWRGD_CHE_CPU0_DIMM1 ; 2 = PWRGD_FAIL_CPU0_EF
R886  Q_RES  33.2 1% CHIP  pkg 0402LF  page 114 : 1 = PWRGD_CHE_CPU0_DIMM2 ; 2 = PWRGD_FAIL_CPU0_EF
R889  Q_RES  33.2 1% CHIP  pkg 0402LF  page 114 : 1 = PWRGD_CHG_CPU0_DIMM1 ; 2 = PWRGD_FAIL_CPU0_GH
R890  Q_RES  33.2 1% CHIP  pkg 0402LF  page 114 : 1 = PWRGD_CHG_CPU0_DIMM2 ; 2 = PWRGD_FAIL_CPU0_GH
R893  Q_RES  33.2 1% CHIP  pkg 0402LF  page 114 : 1 = PWRGD_CHA_CPU1_DIMM1 ; 2 = PWRGD_FAIL_CPU1_AB
R894  Q_RES  33.2 1% CHIP  pkg 0402LF  page 114 : 1 = PWRGD_CHA_CPU1_DIMM2 ; 2 = PWRGD_FAIL_CPU1_AB
R895  Q_RES  33.2 1% CHIP  pkg 0402LF  page 114 : 1 = PWRGD_CHB_CPU1_DIMM1 ; 2 = PWRGD_FAIL_CPU1_AB
R896  Q_RES  33.2 1% CHIP  pkg 0402LF  page 114 : 1 = PWRGD_CHB_CPU1_DIMM2 ; 2 = PWRGD_FAIL_CPU1_AB
R897  Q_RES  33.2 1% CHIP  pkg 0402LF  page 114 : 1 = PWRGD_CHC_CPU1_DIMM1 ; 2 = PWRGD_FAIL_CPU1_CD
R898  Q_RES  33.2 1% CHIP  pkg 0402LF  page 114 : 1 = PWRGD_CHC_CPU1_DIMM2 ; 2 = PWRGD_FAIL_CPU1_CD
R899  Q_RES  33.2 1% CHIP  pkg 0402LF  page 114 : 1 = PWRGD_CHD_CPU1_DIMM1 ; 2 = PWRGD_FAIL_CPU1_CD
R900  Q_RES  33.2 1% CHIP  pkg 0402LF  page 114 : 1 = PWRGD_CHD_CPU1_DIMM2 ; 2 = PWRGD_FAIL_CPU1_CD
R901  Q_RES  33.2 1% CHIP  pkg 0402LF  page 114 : 1 = PWRGD_CHE_CPU1_DIMM1 ; 2 = PWRGD_FAIL_CPU1_EF
R902  Q_RES  33.2 1% CHIP  pkg 0402LF  page 114 : 1 = PWRGD_CHE_CPU1_DIMM2 ; 2 = PWRGD_FAIL_CPU1_EF
R903  Q_RES  33.2 1% CHIP  pkg 0402LF  page 114 : 1 = PWRGD_CHF_CPU1_DIMM1 ; 2 = PWRGD_FAIL_CPU1_EF
R905  Q_RES  33.2 1% CHIP  pkg 0402LF  page 114 : 1 = PWRGD_CHG_CPU1_DIMM1 ; 2 = PWRGD_FAIL_CPU1_GH
R906  Q_RES  33.2 1% CHIP  pkg 0402LF  page 114 : 1 = PWRGD_CHG_CPU1_DIMM2 ; 2 = PWRGD_FAIL_CPU1_GH
R907  Q_RES  33.2 1% CHIP  pkg 0402LF  page 114 : 1 = PWRGD_CHH_CPU1_DIMM1 ; 2 = PWRGD_FAIL_CPU1_GH
R908  Q_RES  33.2 1% CHIP  pkg 0402LF  page 114 : 1 = PWRGD_CHH_CPU1_DIMM2 ; 2 = PWRGD_FAIL_CPU1_GH
R909  Q_RES  33.2 1% CHIP  pkg 0402LF  page 235 : 1 = SMB_PEHPCPU0_GTL_SDA ; 2 = SMB_PEHPCPU0_GTL_R_SDA
R910  Q_RES  240 1% CHIP  pkg 0402LF  page 235 : 1 = PVNN_TERM_CPU0 ; 2 = SMB_PEHPCPU0_GTL_R_SCL
R911  Q_RES  240 1% CHIP  pkg 0402LF  page 235 : 1 = PVNN_TERM_CPU0 ; 2 = SMB_PEHPCPU0_GTL_R_SDA
R912  Q_RES  4.75K 1% EMPTY  pkg 0402LF  page 208 : 1 = P3V3_AUX ; 2 = CLK_CK440_SMB_ADDR0
R913  Q_RES  10K 1% CHIP  pkg 0402LF  page 183 : 1 = PU_OC6_USB_N ; 2 = P3V3_AUX
R915  Q_RES  0 5% CHIP  pkg 0402LF  page 185 : 1 = SPI_PCH_IO0 ; 2 = SPI_SYS_MOSI
R916  Q_RES  0 5% CHIP  pkg 0402LF  page 185 : 1 = SPI_PCH_IO1 ; 2 = SPI_SYS_MISO
R917  Q_RES  0 5% CHIP  pkg 0402LF  page 185 : 1 = SPI_PCH_IO3 ; 2 = SPI_SYS_HOLD_IO3
R918  Q_RES  0 5% CHIP  pkg 0402LF  page 185 : 1 = SPI_PCH_IO2 ; 2 = SPI_SYS_WP_IO2
R919  Q_RES  10K 1% CHIP  pkg 0402LF  page 221 : 1 = P3V3_AUX ; 2 = JTAG_PLD_JTAGEN
R920  Q_RES  1K 1% EMPTY  pkg 0402LF  page 221 : 1 = JTAG_PLD_JTAGEN ; 2 = GND
R927  Q_RES  10K 1% CHIP  pkg 0402LF  page 221 : 1 = P3V3_AUX ; 2 = JTAG_BMC_PLD_TDI
R928  Q_RES  10K 1% CHIP  pkg 0402LF  page 221 : 1 = P3V3_AUX ; 2 = JTAG_BMC_PLD_TDO
R929  Q_RES  10K 1% CHIP  pkg 0402LF  page 221 : 1 = P3V3_AUX ; 2 = JTAG_BMC_PLD_TMS
R930  Q_RES  4.7K 1% CHIP  pkg 0402LF  page 221 : 1 = JTAG_BMC_PLD_TCK ; 2 = GND
R932  Q_RES  10K 1% CHIP  pkg 0402LF  page 128 : 1 = RST_CPU0_DRAM_AB_N ; 2 = GND
R933  Q_RES  10K 1% CHIP  pkg 0402LF  page 128 : 1 = RST_CPU1_DRAM_AB_N ; 2 = GND
R934  Q_RES  10K 1% CHIP  pkg 0402LF  page 128 : 1 = RST_CPU0_DRAM_CD_N ; 2 = GND
R935  Q_RES  10K 1% CHIP  pkg 0402LF  page 128 : 1 = RST_CPU1_DRAM_CD_N ; 2 = GND
R936  Q_RES  10K 1% CHIP  pkg 0402LF  page 128 : 1 = RST_CPU0_DRAM_EF_N ; 2 = GND
R937  Q_RES  10K 1% CHIP  pkg 0402LF  page 128 : 1 = RST_CPU1_DRAM_EF_N ; 2 = GND
R938  Q_RES  10K 1% CHIP  pkg 0402LF  page 128 : 1 = RST_CPU0_DRAM_GH_N ; 2 = GND
R939  Q_RES  10K 1% CHIP  pkg 0402LF  page 128 : 1 = RST_CPU1_DRAM_GH_N ; 2 = GND
R940  Q_RES  10K 1% CHIP  pkg 0402LF  page 115 : 1 = P3V3_AUX ; 2 = PWRGD_FAIL_CPU0_AB_R1
R941  Q_RES  10K 1% CHIP  pkg 0402LF  page 115 : 1 = P3V3_AUX ; 2 = PWRGD_FAIL_CPU0_CD_R1
R942  Q_RES  10K 1% CHIP  pkg 0402LF  page 115 : 1 = P3V3_AUX ; 2 = PWRGD_FAIL_CPU0_EF_R1
R943  Q_RES  10K 1% CHIP  pkg 0402LF  page 115 : 1 = P3V3_AUX ; 2 = PWRGD_FAIL_CPU0_GH_R1
R944  Q_RES  10K 1% CHIP  pkg 0402LF  page 115 : 1 = P3V3_AUX ; 2 = PWRGD_FAIL_CPU1_AB_R1
R945  Q_RES  10K 1% CHIP  pkg 0402LF  page 115 : 1 = P3V3_AUX ; 2 = PWRGD_FAIL_CPU1_CD_R1
R946  Q_RES  10K 1% CHIP  pkg 0402LF  page 115 : 1 = P3V3_AUX ; 2 = PWRGD_FAIL_CPU1_EF_R1
R947  Q_RES  10K 1% CHIP  pkg 0402LF  page 115 : 1 = P3V3_AUX ; 2 = PWRGD_FAIL_CPU1_GH_R1
R953  Q_RES  4.75K 1% CHIP  pkg 0402LF  page 208 : 1 = CLK_CK440_SMB_ADDR0 ; 2 = GND
R960  Q_RES  33.2 1% CHIP  pkg 0402LF  page 235 : 1 = SMB_PEHPCPU0_GTL_SCL ; 2 = SMB_PEHPCPU0_GTL_R_SCL
R961  Q_RES  33.2 1% CHIP  pkg 0402LF  page 235 : 1 = SMB_PEHPCPU1_GTL_SCL ; 2 = SMB_PEHPCPU1_GTL_R_SCL
